(kicad_pcb
	(version 20260206)
	(generator "pcbnew")
	(generator_version "10.0")
	(general
		(thickness 1.6)
		(legacy_teardrops no)
	)
	(paper "A4")
	(title_block
		(title "04192023_DAF0TMB3IC0_F0TG_MB_C_brd_V02_OCP.brd")
		(comment 1 "Grand Teton / footprint 655 of 8354 (U6013), pads 112-223 of 354")
	)
	(layers
		(0 "F.Cu" signal "TOP")
		(4 "In1.Cu" signal "GND")
		(6 "In2.Cu" signal "IN1")
		(8 "In3.Cu" signal "GND1")
		(10 "In4.Cu" signal "IN2")
		(12 "In5.Cu" signal "GND2")
		(14 "In6.Cu" signal "IN3")
		(16 "In7.Cu" signal "GND3")
		(18 "In8.Cu" signal "VCC")
		(20 "In9.Cu" signal "VCC1")
		(22 "In10.Cu" signal "GND4")
		(24 "In11.Cu" signal "IN4")
		(26 "In12.Cu" signal "GND5")
		(28 "In13.Cu" signal "IN5")
		(30 "In14.Cu" signal "GND6")
		(32 "In15.Cu" signal "IN6")
		(34 "In16.Cu" signal "GND7")
		(2 "B.Cu" signal "BOTTOM")
		(9 "F.Adhes" user "F.Adhesive")
		(11 "B.Adhes" user "B.Adhesive")
		(13 "F.Paste" user "Package Geometry/Pastemask Top")
		(15 "B.Paste" user "Package Geometry/Pastemask Bottom")
		(5 "F.SilkS" user "Ref Des/Silkscreen Top")
		(7 "B.SilkS" user "Ref Des/Silkscreen Bottom")
		(1 "F.Mask" user "Board Geometry/Soldermask Top")
		(3 "B.Mask" user "Board Geometry/Soldermask Bottom")
		(17 "Dwgs.User" user "User.Drawings")
		(19 "Cmts.User" user "User.Comments")
		(21 "Eco1.User" user "User.Eco1")
		(23 "Eco2.User" user "User.Eco2")
		(25 "Edge.Cuts" user "Board Geometry/Outline")
		(27 "Margin" user)
		(31 "F.CrtYd" user "Package Geometry/Place Bound Top")
		(29 "B.CrtYd" user "Package Geometry/Place Bound Bottom")
		(35 "F.Fab" user "Ref Des/Assembly Top")
		(33 "B.Fab" user "Ref Des/Assembly Bottom")
	)
	(footprint ""
		(layer "F.Cu")
		(at 379.567948 -395.724634)
		(property "Reference" "U6013"
			(at -8.471916 -7.649972 0)
			(unlocked yes)
			(layer "F.SilkS")
			(effects
				(font
					(size 0.7874 0.5842)
					(thickness 0.1524)
				)
				(justify left)
			)
		)
		(property "Value" ""
			(at 0 0 0)
			(layer "F.Fab")
			(effects
				(font
					(size 1.27 1.27)
				)
			)
		)
		(duplicate_pad_numbers_are_jumpers no)
		(pad "BV32" smd circle
			(at 1.20269 2.724912)
			(size 0.381 0.381)
			(layers "F.Cu" "F.Mask" "F.Paste")
			(net "GND")
		)
		(pad "BW2" smd circle
			(at 1.150112 -3.41884)
			(size 0.3048 0.3048)
			(layers "F.Cu" "F.Mask" "F.Paste")
			(net "GND")
		)
		(pad "BW34" smd circle
			(at 1.150112 3.420364)
			(size 0.3048 0.3048)
			(layers "F.Cu" "F.Mask" "F.Paste")
			(net "GND")
		)
		(pad "BY1" smd oval
			(at 0.849884 -3.938524)
			(size 0.254 0.3302)
			(layers "F.Cu" "F.Mask" "F.Paste")
			(net "GND")
		)
		(pad "BY35" smd oval
			(at 0.849884 3.940048)
			(size 0.254 0.3302)
			(layers "F.Cu" "F.Mask" "F.Paste")
			(net "GND")
		)
		(pad "C2" smd circle
			(at 10.750042 -3.41884)
			(size 0.3048 0.3048)
			(layers "F.Cu" "F.Mask" "F.Paste")
			(net "NCF_CPU0_P3_GND")
		)
		(pad "C34" smd circle
			(at 10.750042 3.420364)
			(size 0.3048 0.3048)
			(layers "F.Cu" "F.Mask" "F.Paste")
			(net "NCF_CPU0_P3_GND")
		)
		(pad "CA7" smd circle
			(at 0.80264 -2.12471)
			(size 0.381 0.381)
			(layers "F.Cu" "F.Mask" "F.Paste")
			(net "P5E_CPU0_P3_TX_BUF_DP<8>")
		)
		(pad "CA26" smd circle
			(at 0.80264 1.339342)
			(size 0.381 0.381)
			(layers "F.Cu" "F.Mask" "F.Paste")
			(net "P5E_CPU0_P3_RX_DP<8>")
		)
		(pad "CB2" smd circle
			(at 0.54991 -3.41884)
			(size 0.3048 0.3048)
			(layers "F.Cu" "F.Mask" "F.Paste")
			(net "P5E_CPU0_P3_RX_BUF_DN<8>")
		)
		(pad "CB34" smd circle
			(at 0.54991 3.420364)
			(size 0.3048 0.3048)
			(layers "F.Cu" "F.Mask" "F.Paste")
			(net "P5E_CPU0_P3_TX_C_DN<8>")
		)
		(pad "CC10" smd circle
			(at 0.40259 -1.431798)
			(size 0.381 0.381)
			(layers "F.Cu" "F.Mask" "F.Paste")
			(net "P5E_CPU0_P3_TX_BUF_DN<8>")
		)
		(pad "CC29" smd circle
			(at 0.40259 2.032254)
			(size 0.381 0.381)
			(layers "F.Cu" "F.Mask" "F.Paste")
			(net "P5E_CPU0_P3_RX_DN<8>")
		)
		(pad "CD1" smd oval
			(at 0.249936 -3.938524)
			(size 0.254 0.3302)
			(layers "F.Cu" "F.Mask" "F.Paste")
			(net "P5E_CPU0_P3_RX_BUF_DP<8>")
		)
		(pad "CD35" smd oval
			(at 0.249936 3.940048)
			(size 0.254 0.3302)
			(layers "F.Cu" "F.Mask" "F.Paste")
			(net "P5E_CPU0_P3_TX_C_DP<8>")
		)
		(pad "CE4" smd circle
			(at 0.00254 -2.817368)
			(size 0.381 0.381)
			(layers "F.Cu" "F.Mask" "F.Paste")
			(net "GND")
		)
		(pad "CE13" smd circle
			(at 0.00254 -0.79629)
			(size 0.3048 0.3048)
			(layers "F.Cu" "F.Mask" "F.Paste")
			(net "GND")
		)
		(pad "CE17" smd circle
			(at 0.00254 -0.296164)
			(size 0.3048 0.3048)
			(layers "F.Cu" "F.Mask" "F.Paste")
			(net "P1V8_CPU0_RT3_1A")
		)
		(pad "CE20" smd circle
			(at 0.00254 0.203708)
			(size 0.3048 0.3048)
			(layers "F.Cu" "F.Mask" "F.Paste")
			(net "P1V8_CPU0_RT3_1A")
		)
		(pad "CE22" smd circle
			(at 0.00254 0.703834)
			(size 0.3048 0.3048)
			(layers "F.Cu" "F.Mask" "F.Paste")
			(net "GND")
		)
		(pad "CE32" smd circle
			(at 0.00254 2.724912)
			(size 0.381 0.381)
			(layers "F.Cu" "F.Mask" "F.Paste")
			(net "GND")
		)
		(pad "CF2" smd circle
			(at -0.050038 -3.41884)
			(size 0.3048 0.3048)
			(layers "F.Cu" "F.Mask" "F.Paste")
			(net "GND")
		)
		(pad "CF34" smd circle
			(at -0.050038 3.420364)
			(size 0.3048 0.3048)
			(layers "F.Cu" "F.Mask" "F.Paste")
			(net "GND")
		)
		(pad "CG1" smd oval
			(at -0.350012 -3.938524)
			(size 0.254 0.3302)
			(layers "F.Cu" "F.Mask" "F.Paste")
			(net "GND")
		)
		(pad "CG35" smd oval
			(at -0.350012 3.940048)
			(size 0.254 0.3302)
			(layers "F.Cu" "F.Mask" "F.Paste")
			(net "GND")
		)
		(pad "CH7" smd circle
			(at -0.39751 -2.12471)
			(size 0.381 0.381)
			(layers "F.Cu" "F.Mask" "F.Paste")
			(net "P5E_CPU0_P3_TX_BUF_DP<7>")
		)
		(pad "CH26" smd circle
			(at -0.39751 1.339342)
			(size 0.381 0.381)
			(layers "F.Cu" "F.Mask" "F.Paste")
			(net "P5E_CPU0_P3_RX_DP<7>")
		)
		(pad "CJ2" smd circle
			(at -0.649986 -3.41884)
			(size 0.3048 0.3048)
			(layers "F.Cu" "F.Mask" "F.Paste")
			(net "P5E_CPU0_P3_RX_BUF_DN<7>")
		)
		(pad "CJ34" smd circle
			(at -0.649986 3.420364)
			(size 0.3048 0.3048)
			(layers "F.Cu" "F.Mask" "F.Paste")
			(net "P5E_CPU0_P3_TX_C_DN<7>")
		)
		(pad "CK10" smd circle
			(at -0.797306 -1.431798)
			(size 0.381 0.381)
			(layers "F.Cu" "F.Mask" "F.Paste")
			(net "P5E_CPU0_P3_TX_BUF_DN<7>")
		)
		(pad "CK29" smd circle
			(at -0.797306 2.032254)
			(size 0.381 0.381)
			(layers "F.Cu" "F.Mask" "F.Paste")
			(net "P5E_CPU0_P3_RX_DN<7>")
		)
		(pad "CL1" smd oval
			(at -0.94996 -3.938524)
			(size 0.254 0.3302)
			(layers "F.Cu" "F.Mask" "F.Paste")
			(net "P5E_CPU0_P3_RX_BUF_DP<7>")
		)
		(pad "CL35" smd oval
			(at -0.94996 3.940048)
			(size 0.254 0.3302)
			(layers "F.Cu" "F.Mask" "F.Paste")
			(net "P5E_CPU0_P3_TX_C_DP<7>")
		)
		(pad "CM4" smd circle
			(at -1.197356 -2.817368)
			(size 0.381 0.381)
			(layers "F.Cu" "F.Mask" "F.Paste")
			(net "GND")
		)
		(pad "CM13" smd circle
			(at -1.197356 -0.79629)
			(size 0.3048 0.3048)
			(layers "F.Cu" "F.Mask" "F.Paste")
			(net "GND")
		)
		(pad "CM17" smd circle
			(at -1.197356 -0.296164)
			(size 0.3048 0.3048)
			(layers "F.Cu" "F.Mask" "F.Paste")
			(net "P1V8_CPU0_RT3_1A")
		)
		(pad "CM20" smd circle
			(at -1.197356 0.203708)
			(size 0.3048 0.3048)
			(layers "F.Cu" "F.Mask" "F.Paste")
			(net "P1V8_CPU0_RT3_1A")
		)
		(pad "CM22" smd circle
			(at -1.197356 0.703834)
			(size 0.3048 0.3048)
			(layers "F.Cu" "F.Mask" "F.Paste")
			(net "GND")
		)
		(pad "CM32" smd circle
			(at -1.197356 2.724912)
			(size 0.381 0.381)
			(layers "F.Cu" "F.Mask" "F.Paste")
			(net "GND")
		)
		(pad "CN2" smd circle
			(at -1.249934 -3.41884)
			(size 0.3048 0.3048)
			(layers "F.Cu" "F.Mask" "F.Paste")
			(net "GND")
		)
		(pad "CN34" smd circle
			(at -1.249934 3.420364)
			(size 0.3048 0.3048)
			(layers "F.Cu" "F.Mask" "F.Paste")
			(net "GND")
		)
		(pad "CP1" smd oval
			(at -1.549908 -3.938524)
			(size 0.254 0.3302)
			(layers "F.Cu" "F.Mask" "F.Paste")
			(net "GND")
		)
		(pad "CP35" smd oval
			(at -1.549908 3.940048)
			(size 0.254 0.3302)
			(layers "F.Cu" "F.Mask" "F.Paste")
			(net "GND")
		)
		(pad "CR7" smd circle
			(at -1.597406 -2.12471)
			(size 0.381 0.381)
			(layers "F.Cu" "F.Mask" "F.Paste")
			(net "P5E_CPU0_P3_TX_BUF_DP<6>")
		)
		(pad "CR26" smd circle
			(at -1.597406 1.339342)
			(size 0.381 0.381)
			(layers "F.Cu" "F.Mask" "F.Paste")
			(net "P5E_CPU0_P3_RX_DP<6>")
		)
		(pad "CT2" smd circle
			(at -1.849882 -3.41884)
			(size 0.3048 0.3048)
			(layers "F.Cu" "F.Mask" "F.Paste")
			(net "P5E_CPU0_P3_RX_BUF_DN<6>")
		)
		(pad "CT34" smd circle
			(at -1.849882 3.420364)
			(size 0.3048 0.3048)
			(layers "F.Cu" "F.Mask" "F.Paste")
			(net "P5E_CPU0_P3_TX_C_DN<6>")
		)
		(pad "CU10" smd circle
			(at -1.997456 -1.431798)
			(size 0.381 0.381)
			(layers "F.Cu" "F.Mask" "F.Paste")
			(net "P5E_CPU0_P3_TX_BUF_DN<6>")
		)
		(pad "CU29" smd circle
			(at -1.997456 2.032254)
			(size 0.381 0.381)
			(layers "F.Cu" "F.Mask" "F.Paste")
			(net "P5E_CPU0_P3_RX_DN<6>")
		)
		(pad "CV1" smd oval
			(at -2.15011 -3.938524)
			(size 0.254 0.3302)
			(layers "F.Cu" "F.Mask" "F.Paste")
			(net "P5E_CPU0_P3_RX_BUF_DP<6>")
		)
		(pad "CV35" smd oval
			(at -2.15011 3.940048)
			(size 0.254 0.3302)
			(layers "F.Cu" "F.Mask" "F.Paste")
			(net "P5E_CPU0_P3_TX_C_DP<6>")
		)
		(pad "CW4" smd circle
			(at -2.397506 -2.817368)
			(size 0.381 0.381)
			(layers "F.Cu" "F.Mask" "F.Paste")
			(net "GND")
		)
		(pad "CW13" smd circle
			(at -2.397506 -0.79629)
			(size 0.3048 0.3048)
			(layers "F.Cu" "F.Mask" "F.Paste")
			(net "GND")
		)
		(pad "CW17" smd circle
			(at -2.397506 -0.296164)
			(size 0.3048 0.3048)
			(layers "F.Cu" "F.Mask" "F.Paste")
			(net "P0V9_CPU0_RT_2D")
		)
		(pad "CW20" smd circle
			(at -2.397506 0.203708)
			(size 0.3048 0.3048)
			(layers "F.Cu" "F.Mask" "F.Paste")
			(net "P0V9_CPU0_RT_2D")
		)
		(pad "CW22" smd circle
			(at -2.397506 0.703834)
			(size 0.3048 0.3048)
			(layers "F.Cu" "F.Mask" "F.Paste")
			(net "GND")
		)
		(pad "CW32" smd circle
			(at -2.397506 2.724912)
			(size 0.381 0.381)
			(layers "F.Cu" "F.Mask" "F.Paste")
			(net "GND")
		)
		(pad "CY2" smd circle
			(at -2.450084 -3.41884)
			(size 0.3048 0.3048)
			(layers "F.Cu" "F.Mask" "F.Paste")
			(net "GND")
		)
		(pad "CY34" smd circle
			(at -2.450084 3.420364)
			(size 0.3048 0.3048)
			(layers "F.Cu" "F.Mask" "F.Paste")
			(net "GND")
		)
		(pad "D1" smd oval
			(at 10.450068 -3.938524)
			(size 0.254 0.3302)
			(layers "F.Cu" "F.Mask" "F.Paste")
			(net "NCF_CPU0_P3_GND")
		)
		(pad "D35" smd oval
			(at 10.450068 3.940048)
			(size 0.254 0.3302)
			(layers "F.Cu" "F.Mask" "F.Paste")
			(net "NCF_CPU0_P3_GND")
		)
		(pad "DA1" smd oval
			(at -2.750058 -3.938524)
			(size 0.254 0.3302)
			(layers "F.Cu" "F.Mask" "F.Paste")
			(net "GND")
		)
		(pad "DA35" smd oval
			(at -2.750058 3.940048)
			(size 0.254 0.3302)
			(layers "F.Cu" "F.Mask" "F.Paste")
			(net "GND")
		)
		(pad "DB7" smd circle
			(at -2.797302 -2.12471)
			(size 0.381 0.381)
			(layers "F.Cu" "F.Mask" "F.Paste")
			(net "P5E_CPU0_P3_TX_BUF_DP<5>")
		)
		(pad "DB26" smd circle
			(at -2.797302 1.339342)
			(size 0.381 0.381)
			(layers "F.Cu" "F.Mask" "F.Paste")
			(net "P5E_CPU0_P3_RX_DP<5>")
		)
		(pad "DC2" smd circle
			(at -3.050032 -3.41884)
			(size 0.3048 0.3048)
			(layers "F.Cu" "F.Mask" "F.Paste")
			(net "P5E_CPU0_P3_RX_BUF_DN<5>")
		)
		(pad "DC34" smd circle
			(at -3.050032 3.420364)
			(size 0.3048 0.3048)
			(layers "F.Cu" "F.Mask" "F.Paste")
			(net "P5E_CPU0_P3_TX_C_DN<5>")
		)
		(pad "DD10" smd circle
			(at -3.197352 -1.431798)
			(size 0.381 0.381)
			(layers "F.Cu" "F.Mask" "F.Paste")
			(net "P5E_CPU0_P3_TX_BUF_DN<5>")
		)
		(pad "DD29" smd circle
			(at -3.197352 2.032254)
			(size 0.381 0.381)
			(layers "F.Cu" "F.Mask" "F.Paste")
			(net "P5E_CPU0_P3_RX_DN<5>")
		)
		(pad "DE1" smd oval
			(at -3.350006 -3.938524)
			(size 0.254 0.3302)
			(layers "F.Cu" "F.Mask" "F.Paste")
			(net "P5E_CPU0_P3_RX_BUF_DP<5>")
		)
		(pad "DE35" smd oval
			(at -3.350006 3.940048)
			(size 0.254 0.3302)
			(layers "F.Cu" "F.Mask" "F.Paste")
			(net "P5E_CPU0_P3_TX_C_DP<5>")
		)
		(pad "DF4" smd circle
			(at -3.597402 -2.817368)
			(size 0.381 0.381)
			(layers "F.Cu" "F.Mask" "F.Paste")
			(net "GND")
		)
		(pad "DF13" smd circle
			(at -3.597402 -0.79629)
			(size 0.3048 0.3048)
			(layers "F.Cu" "F.Mask" "F.Paste")
			(net "GND")
		)
		(pad "DF17" smd circle
			(at -3.597402 -0.296164)
			(size 0.3048 0.3048)
			(layers "F.Cu" "F.Mask" "F.Paste")
			(net "P0V9_CPU0_RT3_2A_2D")
		)
		(pad "DF20" smd circle
			(at -3.597402 0.203708)
			(size 0.3048 0.3048)
			(layers "F.Cu" "F.Mask" "F.Paste")
			(net "P0V9_CPU0_RT3_2A_2D")
		)
		(pad "DF22" smd circle
			(at -3.597402 0.703834)
			(size 0.3048 0.3048)
			(layers "F.Cu" "F.Mask" "F.Paste")
			(net "GND")
		)
		(pad "DF32" smd circle
			(at -3.597402 2.724912)
			(size 0.381 0.381)
			(layers "F.Cu" "F.Mask" "F.Paste")
			(net "GND")
		)
		(pad "DG2" smd circle
			(at -3.64998 -3.41884)
			(size 0.3048 0.3048)
			(layers "F.Cu" "F.Mask" "F.Paste")
			(net "GND")
		)
		(pad "DG34" smd circle
			(at -3.64998 3.420364)
			(size 0.3048 0.3048)
			(layers "F.Cu" "F.Mask" "F.Paste")
			(net "GND")
		)
		(pad "DH1" smd oval
			(at -3.949954 -3.938524)
			(size 0.254 0.3302)
			(layers "F.Cu" "F.Mask" "F.Paste")
			(net "GND")
		)
		(pad "DH35" smd oval
			(at -3.949954 3.940048)
			(size 0.254 0.3302)
			(layers "F.Cu" "F.Mask" "F.Paste")
			(net "GND")
		)
		(pad "DJ7" smd circle
			(at -3.997452 -2.12471)
			(size 0.381 0.381)
			(layers "F.Cu" "F.Mask" "F.Paste")
			(net "P5E_CPU0_P3_TX_BUF_DP<4>")
		)
		(pad "DJ26" smd circle
			(at -3.997452 1.339342)
			(size 0.381 0.381)
			(layers "F.Cu" "F.Mask" "F.Paste")
			(net "P5E_CPU0_P3_RX_DP<4>")
		)
		(pad "DK2" smd circle
			(at -4.249928 -3.41884)
			(size 0.3048 0.3048)
			(layers "F.Cu" "F.Mask" "F.Paste")
			(net "P5E_CPU0_P3_RX_BUF_DN<4>")
		)
		(pad "DK34" smd circle
			(at -4.249928 3.420364)
			(size 0.3048 0.3048)
			(layers "F.Cu" "F.Mask" "F.Paste")
			(net "P5E_CPU0_P3_TX_C_DN<4>")
		)
		(pad "DL10" smd circle
			(at -4.397502 -1.431798)
			(size 0.381 0.381)
			(layers "F.Cu" "F.Mask" "F.Paste")
			(net "P5E_CPU0_P3_TX_BUF_DN<4>")
		)
		(pad "DL29" smd circle
			(at -4.397502 2.032254)
			(size 0.381 0.381)
			(layers "F.Cu" "F.Mask" "F.Paste")
			(net "P5E_CPU0_P3_RX_DN<4>")
		)
		(pad "DM1" smd oval
			(at -4.549902 -3.938524)
			(size 0.254 0.3302)
			(layers "F.Cu" "F.Mask" "F.Paste")
			(net "P5E_CPU0_P3_RX_BUF_DP<4>")
		)
		(pad "DM35" smd oval
			(at -4.549902 3.940048)
			(size 0.254 0.3302)
			(layers "F.Cu" "F.Mask" "F.Paste")
			(net "P5E_CPU0_P3_TX_C_DP<4>")
		)
		(pad "DN4" smd circle
			(at -4.797298 -2.817368)
			(size 0.381 0.381)
			(layers "F.Cu" "F.Mask" "F.Paste")
			(net "GND")
		)
		(pad "DN13" smd circle
			(at -4.797298 -0.79629)
			(size 0.3048 0.3048)
			(layers "F.Cu" "F.Mask" "F.Paste")
			(net "GND")
		)
		(pad "DN17" smd circle
			(at -4.797298 -0.296164)
			(size 0.3048 0.3048)
			(layers "F.Cu" "F.Mask" "F.Paste")
			(net "P0V9_CPU0_RT3_2A")
		)
		(pad "DN20" smd circle
			(at -4.797298 0.203708)
			(size 0.3048 0.3048)
			(layers "F.Cu" "F.Mask" "F.Paste")
			(net "P0V9_CPU0_RT3_2A")
		)
		(pad "DN22" smd circle
			(at -4.797298 0.703834)
			(size 0.3048 0.3048)
			(layers "F.Cu" "F.Mask" "F.Paste")
			(net "GND")
		)
		(pad "DN32" smd circle
			(at -4.797298 2.724912)
			(size 0.381 0.381)
			(layers "F.Cu" "F.Mask" "F.Paste")
			(net "GND")
		)
		(pad "DP2" smd circle
			(at -4.849876 -3.41884)
			(size 0.3048 0.3048)
			(layers "F.Cu" "F.Mask" "F.Paste")
			(net "GND")
		)
		(pad "DP34" smd circle
			(at -4.849876 3.420364)
			(size 0.3048 0.3048)
			(layers "F.Cu" "F.Mask" "F.Paste")
			(net "GND")
		)
		(pad "DR1" smd oval
			(at -5.150104 -3.938524)
			(size 0.254 0.3302)
			(layers "F.Cu" "F.Mask" "F.Paste")
			(net "GND")
		)
		(pad "DR35" smd oval
			(at -5.150104 3.940048)
			(size 0.254 0.3302)
			(layers "F.Cu" "F.Mask" "F.Paste")
			(net "GND")
		)
		(pad "DT7" smd circle
			(at -5.197348 -2.12471)
			(size 0.381 0.381)
			(layers "F.Cu" "F.Mask" "F.Paste")
			(net "P5E_CPU0_P3_TX_BUF_DP<3>")
		)
		(pad "DT26" smd circle
			(at -5.197348 1.339342)
			(size 0.381 0.381)
			(layers "F.Cu" "F.Mask" "F.Paste")
			(net "P5E_CPU0_P3_RX_DP<3>")
		)
		(pad "DU2" smd circle
			(at -5.450078 -3.41884)
			(size 0.3048 0.3048)
			(layers "F.Cu" "F.Mask" "F.Paste")
			(net "P5E_CPU0_P3_RX_BUF_DN<3>")
		)
		(pad "DU34" smd circle
			(at -5.450078 3.420364)
			(size 0.3048 0.3048)
			(layers "F.Cu" "F.Mask" "F.Paste")
			(net "P5E_CPU0_P3_TX_C_DN<3>")
		)
		(pad "DV10" smd circle
			(at -5.597398 -1.431798)
			(size 0.381 0.381)
			(layers "F.Cu" "F.Mask" "F.Paste")
			(net "P5E_CPU0_P3_TX_BUF_DN<3>")
		)
		(pad "DV29" smd circle
			(at -5.597398 2.032254)
			(size 0.381 0.381)
			(layers "F.Cu" "F.Mask" "F.Paste")
			(net "P5E_CPU0_P3_RX_DN<3>")
		)
		(pad "DW1" smd oval
			(at -5.750052 -3.938524)
			(size 0.254 0.3302)
			(layers "F.Cu" "F.Mask" "F.Paste")
			(net "P5E_CPU0_P3_RX_BUF_DP<3>")
		)
		(pad "DW35" smd oval
			(at -5.750052 3.940048)
			(size 0.254 0.3302)
			(layers "F.Cu" "F.Mask" "F.Paste")
			(net "P5E_CPU0_P3_TX_C_DP<3>")
		)
		(pad "DY4" smd circle
			(at -5.997448 -2.817368)
			(size 0.381 0.381)
			(layers "F.Cu" "F.Mask" "F.Paste")
			(net "GND")
		)
		(pad "DY13" smd circle
			(at -5.997448 -0.79629)
			(size 0.3048 0.3048)
			(layers "F.Cu" "F.Mask" "F.Paste")
			(net "GND")
		)
		(pad "DY17" smd circle
			(at -5.997448 -0.296164)
			(size 0.3048 0.3048)
			(layers "F.Cu" "F.Mask" "F.Paste")
			(net "P0V9_CPU0_RT3_2A")
		)
		(pad "DY20" smd circle
			(at -5.997448 0.203708)
			(size 0.3048 0.3048)
			(layers "F.Cu" "F.Mask" "F.Paste")
			(net "P0V9_CPU0_RT3_2A")
		)
		(pad "DY22" smd circle
			(at -5.997448 0.703834)
			(size 0.3048 0.3048)
			(layers "F.Cu" "F.Mask" "F.Paste")
			(net "GND")
		)
	)
)
